(kicad_pcb
	(version 20260206)
	(generator "pcbnew")
	(generator_version "10.0")
	(general
		(thickness 1.6)
		(legacy_teardrops no)
	)
	(paper "A4")
	(title_block
		(title "peb — Lightning_PEB_BRD.brd")
		(comment 1 "Lightning (Wiwynn / Facebook NVMe JBOF) / footprint 1445 of 2563 (U1), pads 1289-1311 of 1311")
	)
	(layers
		(0 "F.Cu" signal "TOP")
		(4 "In1.Cu" signal "L2GND")
		(6 "In2.Cu" signal "L3")
		(8 "In3.Cu" signal "L4VCC")
		(10 "In4.Cu" signal "L5VCC")
		(12 "In5.Cu" signal "L6")
		(14 "In6.Cu" signal "L7GND")
		(2 "B.Cu" signal "BOTTOM")
		(9 "F.Adhes" user "F.Adhesive")
		(11 "B.Adhes" user "B.Adhesive")
		(13 "F.Paste" user "Package Geometry/Pastemask Top")
		(15 "B.Paste" user "Package Geometry/Pastemask Bottom")
		(5 "F.SilkS" user "Ref Des/Silkscreen Top")
		(7 "B.SilkS" user "Ref Des/Silkscreen Bottom")
		(1 "F.Mask" user "Board Geometry/Soldermask Top")
		(3 "B.Mask" user "Board Geometry/Soldermask Bottom")
		(17 "Dwgs.User" user "User.Drawings")
		(19 "Cmts.User" user "User.Comments")
		(21 "Eco1.User" user "User.Eco1")
		(23 "Eco2.User" user "User.Eco2")
		(25 "Edge.Cuts" user "Board Geometry/Outline")
		(27 "Margin" user)
		(31 "F.CrtYd" user "Package Geometry/Place Bound Top")
		(29 "B.CrtYd" user "Package Geometry/Place Bound Bottom")
		(35 "F.Fab" user "Ref Des/Assembly Top")
		(33 "B.Fab" user "Ref Des/Assembly Bottom")
	)
	(footprint ""
		(layer "F.Cu")
		(at 240.599976 -47.999904 -90)
		(property "Reference" "U1"
			(at 0 0 270)
			(layer "F.SilkS")
			(hide yes)
			(effects
				(font
					(size 1.27 1.27)
				)
			)
		)
		(property "Value" "PM8546A-FEIP-GP"
			(at -25.785064 -6.40334 270)
			(unlocked yes)
			(layer "F.Fab")
			(hide yes)
			(effects
				(font
					(size 1.016 1.016)
					(thickness 0.1524)
				)
			)
		)
		(property "Device Type" "BGA1311C37D5H134"
			(at -25.785064 -7.92734 270)
			(unlocked yes)
			(layer "F.Fab")
			(hide yes)
			(effects
				(font
					(size 1.016 1.016)
					(thickness 0.1524)
				)
			)
		)
		(duplicate_pad_numbers_are_jumpers no)
		(pad "Y15" smd circle
			(at -3.999992 0.999998 270)
			(size 0.4572 0.4572)
			(layers "F.Cu" "F.Mask" "F.Paste")
			(net "DUT_VDD")
		)
		(pad "Y16" smd circle
			(at -2.999994 0.999998 270)
			(size 0.4572 0.4572)
			(layers "F.Cu" "F.Mask" "F.Paste")
			(net "GND")
		)
		(pad "Y17" smd circle
			(at -1.999996 0.999998 270)
			(size 0.4572 0.4572)
			(layers "F.Cu" "F.Mask" "F.Paste")
			(net "DUT_VDD")
		)
		(pad "Y18" smd circle
			(at -0.999998 0.999998 270)
			(size 0.4572 0.4572)
			(layers "F.Cu" "F.Mask" "F.Paste")
			(net "GND")
		)
		(pad "Y19" smd circle
			(at 0 0.999998 270)
			(size 0.4572 0.4572)
			(layers "F.Cu" "F.Mask" "F.Paste")
			(net "DUT_VDD")
		)
		(pad "Y20" smd circle
			(at 0.999998 0.999998 270)
			(size 0.4572 0.4572)
			(layers "F.Cu" "F.Mask" "F.Paste")
			(net "GND")
		)
		(pad "Y21" smd circle
			(at 1.999996 0.999998 270)
			(size 0.4572 0.4572)
			(layers "F.Cu" "F.Mask" "F.Paste")
			(net "DUT_VDD")
		)
		(pad "Y22" smd circle
			(at 2.999994 0.999998 270)
			(size 0.4572 0.4572)
			(layers "F.Cu" "F.Mask" "F.Paste")
			(net "GND")
		)
		(pad "Y23" smd circle
			(at 3.999992 0.999998 270)
			(size 0.4572 0.4572)
			(layers "F.Cu" "F.Mask" "F.Paste")
			(net "DUT_VDD")
		)
		(pad "Y24" smd circle
			(at 4.99999 0.999998 270)
			(size 0.4572 0.4572)
			(layers "F.Cu" "F.Mask" "F.Paste")
			(net "GND")
		)
		(pad "Y25" smd circle
			(at 5.999988 0.999998 270)
			(size 0.4572 0.4572)
			(layers "F.Cu" "F.Mask" "F.Paste")
			(net "DUT_VDD")
		)
		(pad "Y26" smd circle
			(at 6.999986 0.999998 270)
			(size 0.4572 0.4572)
			(layers "F.Cu" "F.Mask" "F.Paste")
			(net "GND")
		)
		(pad "Y27" smd circle
			(at 7.999984 0.999998 270)
			(size 0.4572 0.4572)
			(layers "F.Cu" "F.Mask" "F.Paste")
			(net "BOOTSTRAP_R_9")
		)
		(pad "Y28" smd circle
			(at 8.999982 0.999998 270)
			(size 0.4572 0.4572)
			(layers "F.Cu" "F.Mask" "F.Paste")
			(net "BOOTSTRAP_R_8")
		)
		(pad "Y29" smd circle
			(at 9.99998 0.999998 270)
			(size 0.4572 0.4572)
			(layers "F.Cu" "F.Mask" "F.Paste")
			(net "PCIE_REFCLK_D_P")
		)
		(pad "Y30" smd circle
			(at 10.999978 0.999998 270)
			(size 0.4572 0.4572)
			(layers "F.Cu" "F.Mask" "F.Paste")
			(net "PCIE_REFCLK_D_N")
		)
		(pad "Y31" smd circle
			(at 11.999976 0.999998 270)
			(size 0.4572 0.4572)
			(layers "F.Cu" "F.Mask" "F.Paste")
			(net "GND")
		)
		(pad "Y32" smd circle
			(at 12.999974 0.999998 270)
			(size 0.4572 0.4572)
			(layers "F.Cu" "F.Mask" "F.Paste")
			(net "PCIE_REFCLK_S1_P")
		)
		(pad "Y33" smd circle
			(at 13.999972 0.999998 270)
			(size 0.4572 0.4572)
			(layers "F.Cu" "F.Mask" "F.Paste")
			(net "PCIE_REFCLK_S1_N")
		)
		(pad "Y34" smd circle
			(at 14.99997 0.999998 270)
			(size 0.4572 0.4572)
			(layers "F.Cu" "F.Mask" "F.Paste")
			(net "BOOTSTRAP_R_4")
		)
		(pad "Y35" smd circle
			(at 15.999968 0.999998 270)
			(size 0.4572 0.4572)
			(layers "F.Cu" "F.Mask" "F.Paste")
			(net "GND")
		)
		(pad "Y36" smd circle
			(at 16.999966 0.999998 270)
			(size 0.4572 0.4572)
			(layers "F.Cu" "F.Mask" "F.Paste")
			(net "GND")
		)
		(pad "Y37" smd circle
			(at 17.999964 0.999998 270)
			(size 0.4572 0.4572)
			(layers "F.Cu" "F.Mask" "F.Paste")
			(net "GND")
		)
	)
)
